(kicad_pcb
	(version 20211014)
	(generator pcbnew)
	(general
    (thickness 1.6)
  )
	(paper "A4")
	(title_block
    (title "SA800U (Snapdragon 845) Baseboard")
    (date "2023-10-19")
    (rev "1.0.3")
    (company "Antmicro Ltd.")
    (comment 1 "www.antmicro.com")
		(comment 9 "footprints 253-260 of 589")
	)
	(layers
    (0 "F.Cu" signal)
    (1 "In1.Cu" power)
    (2 "In2.Cu" signal)
    (3 "In3.Cu" signal)
    (4 "In4.Cu" power)
    (31 "B.Cu" signal)
    (32 "B.Adhes" user "B.Adhesive")
    (33 "F.Adhes" user "F.Adhesive")
    (34 "B.Paste" user)
    (35 "F.Paste" user)
    (36 "B.SilkS" user "B.Silkscreen")
    (37 "F.SilkS" user "F.Silkscreen")
    (38 "B.Mask" user)
    (39 "F.Mask" user)
    (40 "Dwgs.User" user "User.Drawings")
    (41 "Cmts.User" user "User.Comments")
    (42 "Eco1.User" user "User.Eco1")
    (43 "Eco2.User" user "User.Eco2")
    (44 "Edge.Cuts" user)
    (45 "Margin" user)
    (46 "B.CrtYd" user "B.Courtyard")
    (47 "F.CrtYd" user "F.Courtyard")
    (48 "B.Fab" user)
    (49 "F.Fab" user)
  )
	(footprint "sa800u-baseboard-hw-footprints:Nexperia_SOD128" (layer "F.Cu")
    (tedit 62816545)
    (at 87.37 94.2 -90)
    (property "Author" "Antmicro")
    (property "License" "Apache-2.0")
    (property "MPN" "PMEG3050EP,115")
    (property "Manufacturer" "Nexperia")
    (property "Sheetfile" "som.kicad_sch")
    (property "Sheetname" "SoM")
    (attr smd)
    (fp_text reference "D38" (at -2.72 -1.09 -90) (layer "F.SilkS")
      (effects (font (size 0.7 0.7) (thickness 0.15)) (justify left bottom))
    )
    (fp_text value "PMEG3050EP,115" (at 0 2.6 -90) (layer "F.Fab")
      (effects (font (size 0.7 0.7) (thickness 0.15)) (justify left bottom))
    )
    (fp_text user "${REFERENCE}" (at -4.37 6.9 -90) (layer "F.Fab") hide
      (effects (font (size 0.7 0.7) (thickness 0.15)) (justify left bottom))
    )
    (fp_text user "Author: Antmicro" (at -4.37 4.5 -90) (layer "F.Fab") hide
      (effects (font (size 0.7 0.7) (thickness 0.15)) (justify left bottom))
    )
    (fp_text user "License: Apache-2.0" (at -4.37 5.7 -90) (layer "F.Fab") hide
      (effects (font (size 0.7 0.7) (thickness 0.15)) (justify left bottom))
    )
    (fp_line (start -2.121 1.284) (end -2.121 1.473) (layer "F.SilkS") (width 0.15))
    (fp_line (start -1.6 -1.4) (end -1.6 1.4) (layer "F.SilkS") (width 0.12))
    (fp_line (start 2.12 1.473) (end 2.12 1.284) (layer "F.SilkS") (width 0.15))
    (fp_line (start -2.121 -1.474) (end -2.121 -1.287) (layer "F.SilkS") (width 0.15))
    (fp_line (start 2.12 -1.474) (end -2.121 -1.474) (layer "F.SilkS") (width 0.15))
    (fp_line (start 2.12 -1.287) (end 2.12 -1.474) (layer "F.SilkS") (width 0.15))
    (fp_line (start -2.121 1.473) (end 2.12 1.473) (layer "F.SilkS") (width 0.15))
    (fp_rect (start -2.8 -1.6) (end 2.8 1.6) (layer "F.CrtYd") (width 0.05) (fill none))
    (fp_line (start 1.993 0.952) (end 2.5 0.952) (layer "F.Fab") (width 0.15))
    (fp_line (start -1.994 -1.347) (end -1.994 1.346) (layer "F.Fab") (width 0.15))
    (fp_line (start 2.5 0.952) (end 2.5 -0.954) (layer "F.Fab") (width 0.15))
    (fp_line (start 1.993 -0.954) (end 1.993 0.952) (layer "F.Fab") (width 0.15))
    (fp_line (start -1.994 -0.954) (end -2.503 -0.954) (layer "F.Fab") (width 0.15))
    (fp_line (start -2.503 0.952) (end -1.994 0.952) (layer "F.Fab") (width 0.15))
    (fp_line (start 2.5 -0.954) (end 1.993 -0.954) (layer "F.Fab") (width 0.15))
    (fp_line (start 1.993 -1.347) (end -1.994 -1.347) (layer "F.Fab") (width 0.15))
    (fp_line (start -1.994 1.346) (end 1.993 1.346) (layer "F.Fab") (width 0.15))
    (fp_line (start -1.994 -0.675) (end -1.321 -1.347) (layer "F.Fab") (width 0.15))
    (fp_line (start 1.993 1.346) (end 1.993 -1.347) (layer "F.Fab") (width 0.15))
    (fp_line (start -2.503 -0.954) (end -2.503 0.952) (layer "F.Fab") (width 0.15))
    (fp_line (start -1.994 0.673) (end -1.321 1.346) (layer "F.Fab") (width 0.15))
    (fp_line (start -1.994 0.952) (end -1.994 -0.954) (layer "F.Fab") (width 0.15))
    (pad "1" smd rect (at -2.298 0 270) (size 0.8096 1.905) (layers "F.Cu" "F.Paste" "F.Mask")
      (net 424 "/SoM/VBAT_SOM") (pinfunction "1") (pintype "passive"))
    (pad "2" smd rect (at 2.297 0 270) (size 0.8096 1.905) (layers "F.Cu" "F.Paste" "F.Mask")
      (net 137 "3V8_SYS") (pinfunction "2") (pintype "passive"))
  )
	(footprint "sa800u-baseboard-hw-footprints:L_Coilcraft_XEL4030" (layer "F.Cu")
    (tedit 6215D867)
    (at 83.3 94.55 90)
    (property "Author" "Antmicro")
    (property "IMax" "")
    (property "ISat" "")
    (property "License" "Apache-2.0")
    (property "MPN" "XEL4030-222MEC")
    (property "Manufacturer" "Coilcraft")
    (property "MaxCur" "6.1A")
    (property "Sheetfile" "psu.kicad_sch")
    (property "Sheetname" "PSU")
    (property "Size" "4x4")
    (property "Val" "2u2/6.1A")
    (attr smd)
    (fp_text reference "L26" (at 2.44 0.38 180) (layer "F.SilkS")
      (effects (font (size 0.7 0.7) (thickness 0.15)) (justify left bottom))
    )
    (fp_text value "L_2u2_6.1A_XEL4030" (at 0 3.35 90) (layer "F.Fab")
      (effects (font (size 0.7 0.7) (thickness 0.15)) (justify left bottom))
    )
    (fp_text user "${REFERENCE}" (at -2.15 4.996 90) (layer "F.Fab") hide
      (effects (font (size 0.7 0.7) (thickness 0.15)) (justify left bottom))
    )
    (fp_text user "License: Apache-2.0" (at -2.15 6.996 90) (layer "F.Fab") hide
      (effects (font (size 0.7 0.7) (thickness 0.15)) (justify left bottom))
    )
    (fp_text user "Author: Antmicro" (at -2.15 5.996 90) (layer "F.Fab") hide
      (effects (font (size 0.7 0.7) (thickness 0.15)) (justify left bottom))
    )
    (fp_line (start -1.8 2.2) (end 1.85 2.199) (layer "F.SilkS") (width 0.15))
    (fp_line (start -1.8 -2.2) (end 1.85 -2.201) (layer "F.SilkS") (width 0.15))
    (fp_rect (start -2.45 -2.45) (end 2.45 2.45) (layer "F.CrtYd") (width 0.05) (fill none))
    (fp_line (start 1.999 -2) (end 1.999 1.999) (layer "F.Fab") (width 0.15))
    (fp_line (start 1.999 1.999) (end -2 1.999) (layer "F.Fab") (width 0.15))
    (fp_line (start -2 -2) (end 1.999 -2) (layer "F.Fab") (width 0.15))
    (fp_line (start -2 1.999) (end -2 -2) (layer "F.Fab") (width 0.15))
    (pad "1" smd rect (at -1.186 0 90) (size 0.98 3.4) (layers "F.Cu" "F.Paste" "F.Mask")
      (net 357 "Net-(C132-Pad2)") (pintype "passive"))
    (pad "2" smd rect (at 1.185 0 90) (size 0.98 3.4) (layers "F.Cu" "F.Paste" "F.Mask")
      (net 137 "3V8_SYS") (pintype "passive"))
  )
	(footprint "sa800u-baseboard-hw-footprints:C_0805_2012Metric" (layer "F.Cu")
    (tedit 5FD9C126)
    (at 85.75 90.3 180)
    (descr "Capacitor SMD 0805")
    (tags "capacitor SMD 0805")
    (property "Author" "Antmicro")
    (property "Dielectric" "")
    (property "License" "Apache-2.0")
    (property "MPN" "GRM21BR60J107ME15L")
    (property "Manufacturer" "Murata")
    (property "Sheetfile" "som.kicad_sch")
    (property "Sheetname" "SoM")
    (property "Val" "100u")
    (property "Voltage" "")
    (attr smd)
    (fp_text reference "C101" (at 1.38 0.93 180) (layer "F.SilkS")
      (effects (font (size 0.7 0.7) (thickness 0.15)) (justify left bottom))
    )
    (fp_text value "C_100u_0805" (at 0 1.947 180) (layer "F.Fab")
      (effects (font (size 0.7 0.7) (thickness 0.15)) (justify left bottom))
    )
    (fp_text user "License: Apache-2.0" (at -1.9 4.947 180) (layer "F.Fab") hide
      (effects (font (size 0.7 0.7) (thickness 0.15)) (justify left bottom))
    )
    (fp_text user "Author: Antmicro" (at -1.9 5.947 180) (layer "F.Fab") hide
      (effects (font (size 0.7 0.7) (thickness 0.15)) (justify left bottom))
    )
    (fp_text user "${REFERENCE}" (at -1.9 3.947 180) (layer "F.Fab") hide
      (effects (font (size 0.7 0.7) (thickness 0.15)) (justify left bottom))
    )
    (fp_line (start -0.3 0.8) (end 0.3 0.8) (layer "F.SilkS") (width 0.15))
    (fp_line (start -0.3 -0.8) (end 0.3 -0.8) (layer "F.SilkS") (width 0.15))
    (fp_rect (start -1.9 -0.93) (end 1.9 0.93) (layer "F.CrtYd") (width 0.05) (fill none))
    (fp_rect (start -0.95 -0.675) (end 0.95 0.675) (layer "F.Fab") (width 0.15) (fill none))
    (pad "1" smd rect (at -1.05 0 180) (size 1.2 1.2) (layers "F.Cu" "F.Paste" "F.Mask")
      (net 424 "/SoM/VBAT_SOM") (pintype "passive"))
    (pad "2" smd rect (at 1.05 0 180) (size 1.2 1.2) (layers "F.Cu" "F.Paste" "F.Mask")
      (net 1 "GND") (pintype "passive"))
  )
	(footprint "sa800u-baseboard-hw-footprints:C_0402_1005Metric" (layer "F.Cu")
    (tedit 616D63CF)
    (at 95.14 91.71 -90)
    (descr "Capacitor SMD 0402")
    (tags "capacitor SMD 0402")
    (property "Author" "Antmicro")
    (property "Dielectric" "X5R")
    (property "License" "Apache-2.0")
    (property "MPN" "GRM155R61H104KE14D")
    (property "Manufacturer" "Murata")
    (property "Sheetfile" "som.kicad_sch")
    (property "Sheetname" "SoM")
    (property "Val" "100n")
    (property "Voltage" "50V")
    (attr smd)
    (fp_text reference "C102" (at 3.72 -0.41 -90) (layer "F.SilkS")
      (effects (font (size 0.7 0.7) (thickness 0.15)) (justify left bottom))
    )
    (fp_text value "C_100n_0402" (at 0 1.4 -90) (layer "F.Fab")
      (effects (font (size 0.7 0.7) (thickness 0.15)) (justify left bottom))
    )
    (fp_text user "License: Apache-2.0" (at -0.932 5.17 -90) (layer "F.Fab") hide
      (effects (font (size 0.7 0.7) (thickness 0.15)) (justify left bottom))
    )
    (fp_text user "${REFERENCE}" (at -0.932 3.168 -90) (layer "F.Fab") hide
      (effects (font (size 0.7 0.7) (thickness 0.15)) (justify left bottom))
    )
    (fp_text user "Author: Antmicro" (at -0.932 4.17 -90) (layer "F.Fab") hide
      (effects (font (size 0.7 0.7) (thickness 0.15)) (justify left bottom))
    )
    (fp_rect (start -0.94 -0.47) (end 0.94 0.47) (layer "F.CrtYd") (width 0.05) (fill none))
    (fp_rect (start -0.499 -0.249) (end 0.499 0.249) (layer "F.Fab") (width 0.15) (fill none))
    (pad "1" smd roundrect (at -0.484 0 270) (size 0.59 0.64) (layers "F.Cu" "F.Paste" "F.Mask") (roundrect_rratio 0.25)
      (net 424 "/SoM/VBAT_SOM") (pintype "passive"))
    (pad "2" smd roundrect (at 0.484 0 270) (size 0.59 0.64) (layers "F.Cu" "F.Paste" "F.Mask") (roundrect_rratio 0.25)
      (net 1 "GND") (pintype "passive"))
  )
	(footprint "sa800u-baseboard-hw-footprints:C_0402_1005Metric" (layer "F.Cu")
    (tedit 616D63CF)
    (at 94.19 91.71 -90)
    (descr "Capacitor SMD 0402")
    (tags "capacitor SMD 0402")
    (property "Author" "Antmicro")
    (property "Dielectric" "")
    (property "License" "Apache-2.0")
    (property "MPN" "MC0402N330J500CT")
    (property "Manufacturer" "Multicomp")
    (property "Sheetfile" "som.kicad_sch")
    (property "Sheetname" "SoM")
    (property "Val" "33p")
    (property "Voltage" "")
    (attr smd)
    (fp_text reference "C103" (at 3.72 -0.41 -90) (layer "F.SilkS")
      (effects (font (size 0.7 0.7) (thickness 0.15)) (justify left bottom))
    )
    (fp_text value "C_33p_0402" (at 0 1.4 -90) (layer "F.Fab")
      (effects (font (size 0.7 0.7) (thickness 0.15)) (justify left bottom))
    )
    (fp_text user "License: Apache-2.0" (at -0.932 5.17 -90) (layer "F.Fab") hide
      (effects (font (size 0.7 0.7) (thickness 0.15)) (justify left bottom))
    )
    (fp_text user "${REFERENCE}" (at -0.932 3.168 -90) (layer "F.Fab") hide
      (effects (font (size 0.7 0.7) (thickness 0.15)) (justify left bottom))
    )
    (fp_text user "Author: Antmicro" (at -0.932 4.17 -90) (layer "F.Fab") hide
      (effects (font (size 0.7 0.7) (thickness 0.15)) (justify left bottom))
    )
    (fp_rect (start -0.94 -0.47) (end 0.94 0.47) (layer "F.CrtYd") (width 0.05) (fill none))
    (fp_rect (start -0.499 -0.249) (end 0.499 0.249) (layer "F.Fab") (width 0.15) (fill none))
    (pad "1" smd roundrect (at -0.484 0 270) (size 0.59 0.64) (layers "F.Cu" "F.Paste" "F.Mask") (roundrect_rratio 0.25)
      (net 424 "/SoM/VBAT_SOM") (pintype "passive"))
    (pad "2" smd roundrect (at 0.484 0 270) (size 0.59 0.64) (layers "F.Cu" "F.Paste" "F.Mask") (roundrect_rratio 0.25)
      (net 1 "GND") (pintype "passive"))
  )
	(footprint "sa800u-baseboard-hw-footprints:C_0402_1005Metric" (layer "F.Cu")
    (tedit 616D63CF)
    (at 93.24 91.71 -90)
    (descr "Capacitor SMD 0402")
    (tags "capacitor SMD 0402")
    (property "Author" "Antmicro")
    (property "Dielectric" "C0G")
    (property "License" "Apache-2.0")
    (property "MPN" "GCM1555C1H100GA16D")
    (property "Manufacturer" "Murata")
    (property "Sheetfile" "som.kicad_sch")
    (property "Sheetname" "SoM")
    (property "Val" "10p")
    (property "Voltage" "50V")
    (attr smd)
    (fp_text reference "C104" (at 3.72 -0.41 -90) (layer "F.SilkS")
      (effects (font (size 0.7 0.7) (thickness 0.15)) (justify left bottom))
    )
    (fp_text value "C_10p_0402" (at 0 1.4 -90) (layer "F.Fab")
      (effects (font (size 0.7 0.7) (thickness 0.15)) (justify left bottom))
    )
    (fp_text user "Author: Antmicro" (at -0.932 4.17 -90) (layer "F.Fab") hide
      (effects (font (size 0.7 0.7) (thickness 0.15)) (justify left bottom))
    )
    (fp_text user "${REFERENCE}" (at -0.932 3.168 -90) (layer "F.Fab") hide
      (effects (font (size 0.7 0.7) (thickness 0.15)) (justify left bottom))
    )
    (fp_text user "License: Apache-2.0" (at -0.932 5.17 -90) (layer "F.Fab") hide
      (effects (font (size 0.7 0.7) (thickness 0.15)) (justify left bottom))
    )
    (fp_rect (start -0.94 -0.47) (end 0.94 0.47) (layer "F.CrtYd") (width 0.05) (fill none))
    (fp_rect (start -0.499 -0.249) (end 0.499 0.249) (layer "F.Fab") (width 0.15) (fill none))
    (pad "1" smd roundrect (at -0.484 0 270) (size 0.59 0.64) (layers "F.Cu" "F.Paste" "F.Mask") (roundrect_rratio 0.25)
      (net 424 "/SoM/VBAT_SOM") (pintype "passive"))
    (pad "2" smd roundrect (at 0.484 0 270) (size 0.59 0.64) (layers "F.Cu" "F.Paste" "F.Mask") (roundrect_rratio 0.25)
      (net 1 "GND") (pintype "passive"))
  )
	(footprint "sa800u-baseboard-hw-footprints:C_0805_2012Metric" (layer "F.Cu")
    (tedit 5FD9C126)
    (at 89.93 92.68 -90)
    (descr "Capacitor SMD 0805")
    (tags "capacitor SMD 0805")
    (property "Author" "Antmicro")
    (property "Dielectric" "")
    (property "License" "Apache-2.0")
    (property "MPN" "GRM21BR60J107ME15L")
    (property "Manufacturer" "Murata")
    (property "Sheetfile" "som.kicad_sch")
    (property "Sheetname" "SoM")
    (property "Val" "100u")
    (property "Voltage" "")
    (attr smd)
    (fp_text reference "C99" (at 3.9 -0.36 -90) (layer "F.SilkS")
      (effects (font (size 0.7 0.7) (thickness 0.15)) (justify left bottom))
    )
    (fp_text value "C_100u_0805" (at 0 1.947 -90) (layer "F.Fab")
      (effects (font (size 0.7 0.7) (thickness 0.15)) (justify left bottom))
    )
    (fp_text user "Author: Antmicro" (at -1.9 5.947 -90) (layer "F.Fab") hide
      (effects (font (size 0.7 0.7) (thickness 0.15)) (justify left bottom))
    )
    (fp_text user "License: Apache-2.0" (at -1.9 4.947 -90) (layer "F.Fab") hide
      (effects (font (size 0.7 0.7) (thickness 0.15)) (justify left bottom))
    )
    (fp_text user "${REFERENCE}" (at -1.9 3.947 -90) (layer "F.Fab") hide
      (effects (font (size 0.7 0.7) (thickness 0.15)) (justify left bottom))
    )
    (fp_line (start -0.3 0.8) (end 0.3 0.8) (layer "F.SilkS") (width 0.15))
    (fp_line (start -0.3 -0.8) (end 0.3 -0.8) (layer "F.SilkS") (width 0.15))
    (fp_rect (start -1.9 -0.93) (end 1.9 0.93) (layer "F.CrtYd") (width 0.05) (fill none))
    (fp_rect (start -0.95 -0.675) (end 0.95 0.675) (layer "F.Fab") (width 0.15) (fill none))
    (pad "1" smd rect (at -1.05 0 270) (size 1.2 1.2) (layers "F.Cu" "F.Paste" "F.Mask")
      (net 424 "/SoM/VBAT_SOM") (pintype "passive"))
    (pad "2" smd rect (at 1.05 0 270) (size 1.2 1.2) (layers "F.Cu" "F.Paste" "F.Mask")
      (net 1 "GND") (pintype "passive"))
  )
	(footprint "sa800u-baseboard-hw-footprints:SW_DIP_SPSTx02_Slide_Copal_CVS-02xB_W5.9mm_P1mm" (layer "F.Cu")
    (tedit 5A4E1407)
    (at 146.7 113.7 90)
    (descr "SMD 2x-dip-switch SPST Copal_CVS-02xB, Slide, row spacing 5.9 mm")
    (tags "SMD DIP Switch SPST Slide 5.9mm")
    (property "Author" "Antmicro")
    (property "License" "Apache-2.0")
    (property "MPN" "CVS-02B")
    (property "Manufacturer" "Nidec")
    (property "Sheetfile" "som.kicad_sch")
    (property "Sheetname" "SoM")
    (attr smd)
    (fp_text reference "SW1" (at 0 -2.2 90) (layer "F.SilkS")
      (effects (font (size 0.7 0.7) (thickness 0.15)) (justify left bottom))
    )
    (fp_text value "SW_CVS-02B" (at 0 2.91 90) (layer "F.Fab")
      (effects (font (size 0.7 0.7) (thickness 0.15)) (justify left bottom))
    )
    (fp_text user "${REFERENCE}" (at -3.6 4.91 90) (layer "F.Fab") hide
      (effects (font (size 0.7 0.7) (thickness 0.15)) (justify left bottom))
    )
    (fp_text user "on" (at -1.5 0.739 180) (layer "F.Fab")
      (effects (font (size 0.7 0.7) (thickness 0.15)) (justify left bottom))
    )
    (fp_text user "Author: Antmicro" (at -3.6 5.908 90) (layer "F.Fab") hide
      (effects (font (size 0.7 0.7) (thickness 0.15)) (justify left bottom))
    )
    (fp_text user "License: Apache-2.0" (at -3.6 6.908 90) (layer "F.Fab") hide
      (effects (font (size 0.7 0.7) (thickness 0.15)) (justify left bottom))
    )
    (fp_line (start -1.561 1.908) (end 1.56 1.908) (layer "F.SilkS") (width 0.15))
    (fp_line (start -1.561 -1.911) (end 1.56 -1.911) (layer "F.SilkS") (width 0.15))
    (fp_circle (center -3.4 -1.1) (end -3.35 -1.06) (layer "F.SilkS") (width 0.15) (fill solid))
    (fp_rect (start -3.6 -2) (end 3.6 2) (layer "F.CrtYd") (width 0.05) (fill none))
    (fp_line (start -1 -0.75) (end -1 -0.25) (layer "F.Fab") (width 0.15))
    (fp_line (start 0.998 0.248) (end -1 0.248) (layer "F.Fab") (width 0.15))
    (fp_line (start 0.998 -0.75) (end -1 -0.75) (layer "F.Fab") (width 0.15))
    (fp_line (start -1 -0.552) (end -0.335 -0.552) (layer "F.Fab") (width 0.15))
    (fp_line (start -1 -0.452) (end -0.335 -0.452) (layer "F.Fab") (width 0.15))
    (fp_line (start -1 0.65) (end -0.335 0.65) (layer "F.Fab") (width 0.15))
    (fp_line (start -0.335 0.248) (end -0.335 0.748) (layer "F.Fab") (width 0.15))
    (fp_line (start -1 0.248) (end -1 0.748) (layer "F.Fab") (width 0.15))
    (fp_line (start -0.335 -0.75) (end -0.335 -0.25) (layer "F.Fab") (width 0.15))
    (fp_line (start -2.351 -0.5) (end -1.351 -1.5) (layer "F.Fab") (width 0.15))
    (fp_line (start -1 0.748) (end 0.998 0.748) (layer "F.Fab") (width 0.15))
    (fp_line (start -1 0.55) (end -0.335 0.55) (layer "F.Fab") (width 0.15))
    (fp_line (start -1 0.45) (end -0.335 0.45) (layer "F.Fab") (width 0.15))
    (fp_line (start -1 -0.652) (end -0.335 -0.652) (layer "F.Fab") (width 0.15))
    (fp_line (start 0.998 0.748) (end 0.998 0.248) (layer "F.Fab") (width 0.15))
    (fp_line (start -1 0.349) (end -0.335 0.349) (layer "F.Fab") (width 0.15))
    (fp_line (start 0.998 -0.25) (end 0.998 -0.75) (layer "F.Fab") (width 0.15))
    (fp_line (start -1 -0.351) (end -0.335 -0.351) (layer "F.Fab") (width 0.15))
    (fp_line (start -1 -0.25) (end 0.998 -0.25) (layer "F.Fab") (width 0.15))
    (fp_rect (start 2.35 1.499) (end -2.351 -1.5) (layer "F.Fab") (width 0.15) (fill none))
    (pad "1" smd rect (at -2.95 -0.5 90) (size 1.2 0.5) (layers "F.Cu" "F.Paste" "F.Mask")
      (net 418 "/SoM/USB_BOOT") (pintype "passive"))
    (pad "2" smd rect (at -2.95 0.5 90) (size 1.2 0.5) (layers "F.Cu" "F.Paste" "F.Mask")
      (net 419 "/SoM/AUTO_ON_N") (pintype "passive"))
    (pad "3" smd rect (at 2.95 0.5 90) (size 1.2 0.5) (layers "F.Cu" "F.Paste" "F.Mask")
      (net 397 "Net-(R69-Pad1)") (pintype "passive"))
    (pad "4" smd rect (at 2.95 -0.5 90) (size 1.2 0.5) (layers "F.Cu" "F.Paste" "F.Mask")
      (net 417 "Net-(R175-Pad2)") (pintype "passive"))
    (pad "SH" smd rect (at 2.15 -1.5 90) (size 0.7 0.7) (layers "F.Cu" "F.Paste" "F.Mask")
      (net 1 "GND") (pinfunction "SH") (pintype "power_in"))
    (pad "SH" smd rect (at -2.15 -1.5 90) (size 0.7 0.7) (layers "F.Cu" "F.Paste" "F.Mask")
      (net 1 "GND") (pinfunction "SH") (pintype "power_in"))
    (pad "SH" smd rect (at 2.15 1.5 90) (size 0.7 0.7) (layers "F.Cu" "F.Paste" "F.Mask")
      (net 1 "GND") (pinfunction "SH") (pintype "power_in"))
    (pad "SH" smd rect (at -2.15 1.5 90) (size 0.7 0.7) (layers "F.Cu" "F.Paste" "F.Mask")
      (net 1 "GND") (pinfunction "SH") (pintype "power_in"))
  )
)
